# BASEBOARD_FAB2 (Tioga Pass) — schematic netlist excerpt (pin names and nets, part order shuffled) for the footprints in the layout excerpt that follows; sources: Cadence DE-HDL packaged netlist, KiCad conversion of Wiwynn_Tioga_Pass_MB.brd

FB25W4  BLM15AG121SN-1GP  pkg DISCRET-G  page 254 : \1\ = XDP_TDI_R ; \2\ = XDP_TDI
R1R15  RES  0 5.0% CHIP  pkg 0603  page 139 : A = P0V9_LAN ; B = P0V9_LAN_I210
C25W22  CAP_A  0.1UF 16V 10% X7R  pkg 0402V  page 143 : A = BMC_M_VREFCA ; B = GND

(kicad_pcb
	(version 20260206)
	(generator "pcbnew")
	(generator_version "10.0")
	(general
		(thickness 1.6)
		(legacy_teardrops no)
	)
	(paper "A4")
	(title_block
		(title "Wiwynn_Tioga_Pass_MB.brd")
		(comment 1 "Tioga Pass / footprints 4002-4004 of 4770")
	)
	(layers
		(0 "F.Cu" signal "TOP")
		(4 "In1.Cu" signal "L2GND")
		(6 "In2.Cu" signal "L3")
		(8 "In3.Cu" signal "L4GND")
		(10 "In4.Cu" signal "L5")
		(12 "In5.Cu" signal "L6GND")
		(14 "In6.Cu" signal "L7VCC")
		(16 "In7.Cu" signal "L8VCC")
		(18 "In8.Cu" signal "L9GND")
		(20 "In9.Cu" signal "L10")
		(22 "In10.Cu" signal "L11GND")
		(24 "In11.Cu" signal "L12")
		(26 "In12.Cu" signal "L13GND")
		(2 "B.Cu" signal "BOTTOM")
		(9 "F.Adhes" user "F.Adhesive")
		(11 "B.Adhes" user "B.Adhesive")
		(13 "F.Paste" user "Package Geometry/Pastemask Top")
		(15 "B.Paste" user "Package Geometry/Pastemask Bottom")
		(5 "F.SilkS" user "Ref Des/Silkscreen Top")
		(7 "B.SilkS" user "Ref Des/Silkscreen Bottom")
		(1 "F.Mask" user "Board Geometry/Soldermask Top")
		(3 "B.Mask" user "Board Geometry/Soldermask Bottom")
		(17 "Dwgs.User" user "User.Drawings")
		(19 "Cmts.User" user "User.Comments")
		(21 "Eco1.User" user "User.Eco1")
		(23 "Eco2.User" user "User.Eco2")
		(25 "Edge.Cuts" user "Board Geometry/Outline")
		(27 "Margin" user)
		(31 "F.CrtYd" user "Package Geometry/Place Bound Top")
		(29 "B.CrtYd" user "Package Geometry/Place Bound Bottom")
		(35 "F.Fab" user "Ref Des/Assembly Top")
		(33 "B.Fab" user "Ref Des/Assembly Bottom")
	)
	(footprint ""
		(layer "B.Cu")
		(at 450.8627 -144.1831 -90)
		(property "Reference" "FB25W4"
			(at 0 0 90)
			(layer "B.SilkS")
			(hide yes)
			(effects
				(font
					(size 1.27 1.27)
				)
				(justify mirror)
			)
		)
		(property "Value" "*"
			(at 0.0127 -7.01675 270)
			(unlocked yes)
			(layer "B.Fab")
			(hide yes)
			(effects
				(font
					(size 0.889 0.889)
					(thickness 0.1524)
				)
				(justify mirror)
			)
		)
		(property "Device Type" "BLM15AG121SN-1GP_DISCRET-G-BLMA"
			(at 0.0127 -8.54075 270)
			(unlocked yes)
			(layer "B.Fab")
			(hide yes)
			(effects
				(font
					(size 0.889 0.889)
					(thickness 0.1524)
				)
				(justify mirror)
			)
		)
		(duplicate_pad_numbers_are_jumpers no)
		(fp_line
			(start 0.508 0.9398)
			(end 0.508 0.8636)
			(stroke
				(width 0.1524)
				(type default)
			)
			(layer "B.SilkS")
		)
		(fp_line
			(start -0.508 -0.9398)
			(end 0.508 -0.9398)
			(stroke
				(width 0.1524)
				(type default)
			)
			(layer "B.SilkS")
		)
		(fp_line
			(start 0.508 -0.9398)
			(end 0.508 0.9398)
			(stroke
				(width 0.1524)
				(type default)
			)
			(layer "B.SilkS")
		)
		(fp_rect
			(start 0.508 0.9398)
			(end -0.508 -0.9398)
			(stroke
				(width 0)
				(type default)
			)
			(fill no)
			(layer "B.CrtYd")
		)
		(fp_rect
			(start 0.508 0.9398)
			(end -0.508 -0.9398)
			(stroke
				(width 0)
				(type default)
			)
			(fill no)
			(layer "B.Fab")
		)
		(pad "1" smd custom
			(at 0 -0.4445 90)
			(size 0.1397 0.1397)
			(layers "B.Cu" "B.Mask" "B.Paste")
			(net "XDP_TDI_R")
			(options
				(clearance outline)
				(anchor circle)
			)
			(primitives
				(gr_poly
					(pts
						(arc
							(start -0.1778 0.2794)
							(mid -0.249642 0.249642)
							(end -0.2794 0.1778)
						)
						(arc
							(start -0.2794 -0.1778)
							(mid -0.249642 -0.249642)
							(end -0.1778 -0.2794)
						)
						(arc
							(start 0.1778 -0.2794)
							(mid 0.249642 -0.249642)
							(end 0.2794 -0.1778)
						)
						(arc
							(start 0.2794 0.1778)
							(mid 0.249642 0.249642)
							(end 0.1778 0.2794)
						)
					)
					(width 0)
					(fill yes)
				)
			)
		)
		(pad "2" smd custom
			(at 0 0.4445 90)
			(size 0.1397 0.1397)
			(layers "B.Cu" "B.Mask" "B.Paste")
			(net "XDP_TDI")
			(options
				(clearance outline)
				(anchor circle)
			)
			(primitives
				(gr_poly
					(pts
						(arc
							(start -0.1778 0.2794)
							(mid -0.249642 0.249642)
							(end -0.2794 0.1778)
						)
						(arc
							(start -0.2794 -0.1778)
							(mid -0.249642 -0.249642)
							(end -0.1778 -0.2794)
						)
						(arc
							(start 0.1778 -0.2794)
							(mid 0.249642 -0.249642)
							(end 0.2794 -0.1778)
						)
						(arc
							(start 0.2794 0.1778)
							(mid 0.249642 0.249642)
							(end 0.1778 0.2794)
						)
					)
					(width 0)
					(fill yes)
				)
			)
		)
	)
	(footprint ""
		(layer "B.Cu")
		(at 420.116 -32.512 90)
		(property "Reference" "C25W22"
			(at 0.8382 -0.67818 90)
			(unlocked yes)
			(layer "B.SilkS")
			(effects
				(font
					(size 0.4064 0.254)
					(thickness 0.1524)
				)
				(justify left mirror)
			)
		)
		(property "Value" ""
			(at 0 0 90)
			(layer "B.Fab")
			(effects
				(font
					(size 1.27 1.27)
				)
				(justify mirror)
			)
		)
		(duplicate_pad_numbers_are_jumpers no)
		(fp_poly
			(pts
				(xy -0.3048 -0.1016) (xy -0.3048 0.9906) (xy 0.3048 0.9906) (xy 0.3048 -0.1016)
			)
			(stroke
				(width 0)
				(type default)
			)
			(fill no)
			(layer "B.CrtYd")
		)
		(fp_line
			(start 0.3048 -0.1016)
			(end 0.3048 0.9906)
			(stroke
				(width 0.1)
				(type default)
			)
			(layer "B.Fab")
		)
		(fp_line
			(start -0.3048 -0.1016)
			(end 0.3048 -0.1016)
			(stroke
				(width 0.1)
				(type default)
			)
			(layer "B.Fab")
		)
		(fp_line
			(start 0.3048 0.9906)
			(end -0.3048 0.9906)
			(stroke
				(width 0.1)
				(type default)
			)
			(layer "B.Fab")
		)
		(fp_line
			(start -0.3048 0.9906)
			(end -0.3048 -0.1016)
			(stroke
				(width 0.1)
				(type default)
			)
			(layer "B.Fab")
		)
		(pad "1" smd rect
			(at 0 0 270)
			(size 0.508 0.508)
			(layers "B.Cu" "B.Mask" "B.Paste")
			(net "BMC_M_VREFCA")
		)
		(pad "2" smd rect
			(at 0 0.889 270)
			(size 0.508 0.508)
			(layers "B.Cu" "B.Mask" "B.Paste")
			(net "GND")
		)
		(zone
			(layer "B.Cu")
			(hatch none 0.5)
			(connect_pads
				(clearance 0)
			)
			(min_thickness 0.25)
			(keepout
				(tracks allowed)
				(vias not_allowed)
				(pads allowed)
				(copperpour not_allowed)
				(footprints allowed)
			)
			(placement
				(enabled no)
				(sheetname "")
			)
			(fill
				(thermal_gap 0.5)
				(thermal_bridge_width 0.5)
				(island_removal_mode 0)
			)
			(polygon
				(pts
					(xy 420.37 -32.766) (xy 420.37 -32.258) (xy 420.751 -32.258) (xy 420.751 -32.766)
				)
			)
		)
		(zone
			(layer "B.Cu")
			(hatch none 0.5)
			(connect_pads
				(clearance 0)
			)
			(min_thickness 0.25)
			(keepout
				(tracks not_allowed)
				(vias allowed)
				(pads allowed)
				(copperpour not_allowed)
				(footprints allowed)
			)
			(placement
				(enabled no)
				(sheetname "")
			)
			(fill
				(thermal_gap 0.5)
				(thermal_bridge_width 0.5)
				(island_removal_mode 0)
			)
			(polygon
				(pts
					(xy 420.751 -32.766) (xy 420.751 -32.258) (xy 420.37 -32.258) (xy 420.37 -32.766)
				)
			)
		)
	)
	(footprint ""
		(layer "B.Cu")
		(at 481.6475 -46.5582 -90)
		(property "Reference" "R1R15"
			(at 0 0 90)
			(layer "B.SilkS")
			(hide yes)
			(effects
				(font
					(size 1.27 1.27)
				)
				(justify mirror)
			)
		)
		(property "Value" ""
			(at 0 0 90)
			(layer "B.Fab")
			(effects
				(font
					(size 1.27 1.27)
				)
				(justify mirror)
			)
		)
		(duplicate_pad_numbers_are_jumpers no)
		(fp_poly
			(pts
				(xy 0.4953 -0.2032) (xy -0.4953 -0.2032) (xy -0.4953 1.6002) (xy 0.4953 1.6002)
			)
			(stroke
				(width 0)
				(type default)
			)
			(fill no)
			(layer "B.CrtYd")
		)
		(fp_line
			(start -0.4953 1.6002)
			(end 0.4953 1.6002)
			(stroke
				(width 0.1)
				(type default)
			)
			(layer "B.Fab")
		)
		(fp_line
			(start 0.4953 1.6002)
			(end 0.4953 -0.2032)
			(stroke
				(width 0.1)
				(type default)
			)
			(layer "B.Fab")
		)
		(fp_line
			(start -0.4953 -0.2032)
			(end -0.4953 1.6002)
			(stroke
				(width 0.1)
				(type default)
			)
			(layer "B.Fab")
		)
		(fp_line
			(start 0.4953 -0.2032)
			(end -0.4953 -0.2032)
			(stroke
				(width 0.1)
				(type default)
			)
			(layer "B.Fab")
		)
		(pad "1" smd rect
			(at 0 0 90)
			(size 0.762 0.889)
			(layers "B.Cu" "B.Mask" "B.Paste")
			(net "P0V9_LAN")
		)
		(pad "2" smd rect
			(at 0 1.397 90)
			(size 0.762 0.889)
			(layers "B.Cu" "B.Mask" "B.Paste")
			(net "P0V9_LAN_I210")
		)
		(zone
			(layer "B.Cu")
			(hatch none 0.5)
			(connect_pads
				(clearance 0)
			)
			(min_thickness 0.25)
			(keepout
				(tracks allowed)
				(vias not_allowed)
				(pads allowed)
				(copperpour not_allowed)
				(footprints allowed)
			)
			(placement
				(enabled no)
				(sheetname "")
			)
			(fill
				(thermal_gap 0.5)
				(thermal_bridge_width 0.5)
				(island_removal_mode 0)
			)
			(polygon
				(pts
					(xy 480.695 -46.9392) (xy 481.203 -46.9392) (xy 481.203 -46.1772) (xy 480.695 -46.1772)
				)
			)
		)
		(zone
			(layer "B.Cu")
			(hatch none 0.5)
			(connect_pads
				(clearance 0)
			)
			(min_thickness 0.25)
			(keepout
				(tracks not_allowed)
				(vias allowed)
				(pads allowed)
				(copperpour not_allowed)
				(footprints allowed)
			)
			(placement
				(enabled no)
				(sheetname "")
			)
			(fill
				(thermal_gap 0.5)
				(thermal_bridge_width 0.5)
				(island_removal_mode 0)
			)
			(polygon
				(pts
					(xy 480.695 -46.1772) (xy 481.203 -46.1772) (xy 481.203 -46.9392) (xy 480.695 -46.9392)
				)
			)
		)
	)
)
